(kicad_pcb
	(version 20260206)
	(generator "pcbnew")
	(generator_version "10.0")
	(general
		(thickness 1.6)
		(legacy_teardrops no)
	)
	(paper "A4")
	(title_block
		(title "pdpb — Lightning_PDPB_BRD.brd")
		(comment 1 "Lightning (Wiwynn / Facebook NVMe JBOF) / footprints 759-765 of 1140")
	)
	(layers
		(0 "F.Cu" signal "TOP")
		(4 "In1.Cu" signal "L2GND")
		(6 "In2.Cu" signal "L3")
		(8 "In3.Cu" signal "L4VCC")
		(10 "In4.Cu" signal "L5VCC")
		(12 "In5.Cu" signal "L6")
		(14 "In6.Cu" signal "L7GND")
		(2 "B.Cu" signal "BOTTOM")
		(9 "F.Adhes" user "F.Adhesive")
		(11 "B.Adhes" user "B.Adhesive")
		(13 "F.Paste" user "Package Geometry/Pastemask Top")
		(15 "B.Paste" user "Package Geometry/Pastemask Bottom")
		(5 "F.SilkS" user "Ref Des/Silkscreen Top")
		(7 "B.SilkS" user "Ref Des/Silkscreen Bottom")
		(1 "F.Mask" user "Board Geometry/Soldermask Top")
		(3 "B.Mask" user "Board Geometry/Soldermask Bottom")
		(17 "Dwgs.User" user "User.Drawings")
		(19 "Cmts.User" user "User.Comments")
		(21 "Eco1.User" user "User.Eco1")
		(23 "Eco2.User" user "User.Eco2")
		(25 "Edge.Cuts" user "Board Geometry/Outline")
		(27 "Margin" user)
		(31 "F.CrtYd" user "Package Geometry/Place Bound Top")
		(29 "B.CrtYd" user "Package Geometry/Place Bound Bottom")
		(35 "F.Fab" user "Ref Des/Assembly Top")
		(33 "B.Fab" user "Ref Des/Assembly Bottom")
	)
	(footprint ""
		(layer "F.Cu")
		(at 43.50004 -453.099932)
		(property "Reference" "LED5"
			(at 0 0 0)
			(layer "F.SilkS")
			(hide yes)
			(effects
				(font
					(size 1.27 1.27)
				)
			)
		)
		(property "Value" "LED-RB-4-GP"
			(at 5.88899 1.80848 0)
			(unlocked yes)
			(layer "F.Fab")
			(hide yes)
			(effects
				(font
					(size 1.016 1.016)
					(thickness 0.1524)
				)
			)
		)
		(property "Device Type" "LED1613-4PH20"
			(at 5.88899 0.28448 0)
			(unlocked yes)
			(layer "F.Fab")
			(hide yes)
			(effects
				(font
					(size 1.016 1.016)
					(thickness 0.1524)
				)
			)
		)
		(duplicate_pad_numbers_are_jumpers no)
		(fp_line
			(start -1.4478 -0.9652)
			(end 1.4478 -0.9652)
			(stroke
				(width 0.1524)
				(type default)
			)
			(layer "F.SilkS")
		)
		(fp_line
			(start -1.4478 0.9652)
			(end -1.4478 -0.9652)
			(stroke
				(width 0.1524)
				(type default)
			)
			(layer "F.SilkS")
		)
		(fp_line
			(start -1.4478 0.9652)
			(end -1.4478 -0.9652)
			(stroke
				(width 0.508)
				(type default)
			)
			(layer "F.SilkS")
		)
		(fp_line
			(start 1.4478 -0.9652)
			(end 1.4478 0.9652)
			(stroke
				(width 0.1524)
				(type default)
			)
			(layer "F.SilkS")
		)
		(fp_line
			(start 1.4478 0.9652)
			(end -1.4478 0.9652)
			(stroke
				(width 0.1524)
				(type default)
			)
			(layer "F.SilkS")
		)
		(fp_rect
			(start -0.8001 0.6477)
			(end 0.8001 -0.6477)
			(stroke
				(width 0)
				(type default)
			)
			(fill no)
			(layer "F.CrtYd")
		)
		(fp_poly
			(pts
				(xy -1.7018 1.2192) (xy -1.7018 -0.06223) (xy -0.8001 -0.06223) (xy -0.8001 0.6477) (xy 0.8001 0.6477)
				(xy 0.8001 -0.6477) (xy -0.8001 -0.6477) (xy -0.8001 -0.0635) (xy -1.7018 -0.0635) (xy -1.7018 -1.2192)
				(xy 1.7018 -1.2192) (xy 1.7018 1.2192)
			)
			(stroke
				(width 0)
				(type default)
			)
			(fill no)
			(layer "F.CrtYd")
		)
		(fp_rect
			(start -1.7018 1.2192)
			(end 1.7018 -1.2192)
			(stroke
				(width 0)
				(type default)
			)
			(fill no)
			(layer "F.Fab")
		)
		(pad "1" smd rect
			(at -0.73025 0.4064)
			(size 0.9144 0.6096)
			(layers "F.Cu" "F.Mask" "F.Paste")
			(net "SSD_ACT_DR5_MOS_N")
		)
		(pad "2" smd rect
			(at -0.73025 -0.4064)
			(size 0.9144 0.6096)
			(layers "F.Cu" "F.Mask" "F.Paste")
			(net "ATTN_LED_DR5_MOS_N")
		)
		(pad "3" smd rect
			(at 0.73025 -0.4064)
			(size 0.9144 0.6096)
			(layers "F.Cu" "F.Mask" "F.Paste")
			(net "DRV_ATTN_5")
		)
		(pad "4" smd rect
			(at 0.73025 0.4064)
			(size 0.9144 0.6096)
			(layers "F.Cu" "F.Mask" "F.Paste")
			(net "DRV_ACT_5")
		)
	)
	(footprint ""
		(layer "F.Cu")
		(at 24.4094 -467.3346 90)
		(property "Reference" "SR1142"
			(at 0 0 90)
			(layer "F.SilkS")
			(hide yes)
			(effects
				(font
					(size 1.27 1.27)
				)
			)
		)
		(property "Value" "4K7R2J-2-GP"
			(at 0.064008 -3.993896 90)
			(unlocked yes)
			(layer "F.Fab")
			(hide yes)
			(effects
				(font
					(size 1.016 1.016)
					(thickness 0.1524)
				)
			)
		)
		(property "Device Type" "R402H16"
			(at 0.064008 -5.517896 90)
			(unlocked yes)
			(layer "F.Fab")
			(hide yes)
			(effects
				(font
					(size 1.016 1.016)
					(thickness 0.1524)
				)
			)
		)
		(duplicate_pad_numbers_are_jumpers no)
		(fp_line
			(start 0.508 -0.9398)
			(end -0.508 -0.9398)
			(stroke
				(width 0.1524)
				(type default)
			)
			(layer "F.SilkS")
		)
		(fp_line
			(start -0.508 -0.9398)
			(end -0.508 0.9398)
			(stroke
				(width 0.1524)
				(type default)
			)
			(layer "F.SilkS")
		)
		(fp_rect
			(start -0.508 0.9398)
			(end 0.508 -0.9398)
			(stroke
				(width 0)
				(type default)
			)
			(fill no)
			(layer "F.CrtYd")
		)
		(fp_rect
			(start -0.508 0.9398)
			(end 0.508 -0.9398)
			(stroke
				(width 0)
				(type default)
			)
			(fill no)
			(layer "F.Fab")
		)
		(pad "1" smd custom
			(at 0 -0.4445 90)
			(size 0.1397 0.1397)
			(layers "F.Cu" "F.Mask" "F.Paste")
			(net "P3V3")
			(options
				(clearance outline)
				(anchor circle)
			)
			(primitives
				(gr_poly
					(pts
						(arc
							(start -0.1778 -0.2794)
							(mid -0.249642 -0.249642)
							(end -0.2794 -0.1778)
						)
						(arc
							(start -0.2794 0.1778)
							(mid -0.249642 0.249642)
							(end -0.1778 0.2794)
						)
						(arc
							(start 0.1778 0.2794)
							(mid 0.249642 0.249642)
							(end 0.2794 0.1778)
						)
						(arc
							(start 0.2794 -0.1778)
							(mid 0.249642 -0.249642)
							(end 0.1778 -0.2794)
						)
					)
					(width 0)
					(fill yes)
				)
			)
		)
		(pad "2" smd custom
			(at 0 0.4445 90)
			(size 0.1397 0.1397)
			(layers "F.Cu" "F.Mask" "F.Paste")
			(net "SSD_ACT_DR10")
			(options
				(clearance outline)
				(anchor circle)
			)
			(primitives
				(gr_poly
					(pts
						(arc
							(start -0.1778 -0.2794)
							(mid -0.249642 -0.249642)
							(end -0.2794 -0.1778)
						)
						(arc
							(start -0.2794 0.1778)
							(mid -0.249642 0.249642)
							(end -0.1778 0.2794)
						)
						(arc
							(start 0.1778 0.2794)
							(mid 0.249642 0.249642)
							(end 0.2794 0.1778)
						)
						(arc
							(start 0.2794 -0.1778)
							(mid 0.249642 -0.249642)
							(end 0.1778 -0.2794)
						)
					)
					(width 0)
					(fill yes)
				)
			)
		)
	)
	(footprint ""
		(layer "F.Cu")
		(at 96.774 -225.806 90)
		(property "Reference" "R9504"
			(at 0 0 90)
			(layer "F.SilkS")
			(hide yes)
			(effects
				(font
					(size 1.27 1.27)
				)
			)
		)
		(property "Value" "4K7R2J-2-GP"
			(at 0.064008 -3.993896 90)
			(unlocked yes)
			(layer "F.Fab")
			(hide yes)
			(effects
				(font
					(size 1.016 1.016)
					(thickness 0.1524)
				)
			)
		)
		(property "Device Type" "R402H16"
			(at 0.064008 -5.517896 90)
			(unlocked yes)
			(layer "F.Fab")
			(hide yes)
			(effects
				(font
					(size 1.016 1.016)
					(thickness 0.1524)
				)
			)
		)
		(duplicate_pad_numbers_are_jumpers no)
		(fp_line
			(start 0.508 -0.9398)
			(end -0.508 -0.9398)
			(stroke
				(width 0.1524)
				(type default)
			)
			(layer "F.SilkS")
		)
		(fp_line
			(start -0.508 -0.9398)
			(end -0.508 0.9398)
			(stroke
				(width 0.1524)
				(type default)
			)
			(layer "F.SilkS")
		)
		(fp_rect
			(start -0.508 0.9398)
			(end 0.508 -0.9398)
			(stroke
				(width 0)
				(type default)
			)
			(fill no)
			(layer "F.CrtYd")
		)
		(fp_rect
			(start -0.508 0.9398)
			(end 0.508 -0.9398)
			(stroke
				(width 0)
				(type default)
			)
			(fill no)
			(layer "F.Fab")
		)
		(pad "1" smd custom
			(at 0 -0.4445 90)
			(size 0.1397 0.1397)
			(layers "F.Cu" "F.Mask" "F.Paste")
			(net "P3V3")
			(options
				(clearance outline)
				(anchor circle)
			)
			(primitives
				(gr_poly
					(pts
						(arc
							(start -0.1778 -0.2794)
							(mid -0.249642 -0.249642)
							(end -0.2794 -0.1778)
						)
						(arc
							(start -0.2794 0.1778)
							(mid -0.249642 0.249642)
							(end -0.1778 0.2794)
						)
						(arc
							(start 0.1778 0.2794)
							(mid 0.249642 0.249642)
							(end 0.2794 0.1778)
						)
						(arc
							(start 0.2794 -0.1778)
							(mid 0.249642 -0.249642)
							(end 0.1778 -0.2794)
						)
					)
					(width 0)
					(fill yes)
				)
			)
		)
		(pad "2" smd custom
			(at 0 0.4445 90)
			(size 0.1397 0.1397)
			(layers "F.Cu" "F.Mask" "F.Paste")
			(net "SSD7_CLK0_OE_N")
			(options
				(clearance outline)
				(anchor circle)
			)
			(primitives
				(gr_poly
					(pts
						(arc
							(start -0.1778 -0.2794)
							(mid -0.249642 -0.249642)
							(end -0.2794 -0.1778)
						)
						(arc
							(start -0.2794 0.1778)
							(mid -0.249642 0.249642)
							(end -0.1778 0.2794)
						)
						(arc
							(start 0.1778 0.2794)
							(mid 0.249642 0.249642)
							(end 0.2794 0.1778)
						)
						(arc
							(start 0.2794 -0.1778)
							(mid 0.249642 -0.249642)
							(end 0.1778 -0.2794)
						)
					)
					(width 0)
					(fill yes)
				)
			)
		)
	)
	(footprint ""
		(layer "F.Cu")
		(at 39.7383 -100.9269 -90)
		(property "Reference" "R9865"
			(at 0 0 270)
			(layer "F.SilkS")
			(hide yes)
			(effects
				(font
					(size 1.27 1.27)
				)
			)
		)
		(property "Value" "1KR2J-1-GP"
			(at 0.064008 -3.993896 270)
			(unlocked yes)
			(layer "F.Fab")
			(hide yes)
			(effects
				(font
					(size 1.016 1.016)
					(thickness 0.1524)
				)
			)
		)
		(property "Device Type" "R402H16"
			(at 0.064008 -5.517896 270)
			(unlocked yes)
			(layer "F.Fab")
			(hide yes)
			(effects
				(font
					(size 1.016 1.016)
					(thickness 0.1524)
				)
			)
		)
		(duplicate_pad_numbers_are_jumpers no)
		(fp_line
			(start -0.508 -0.9398)
			(end -0.508 0.9398)
			(stroke
				(width 0.1524)
				(type default)
			)
			(layer "F.SilkS")
		)
		(fp_line
			(start 0.508 -0.9398)
			(end -0.508 -0.9398)
			(stroke
				(width 0.1524)
				(type default)
			)
			(layer "F.SilkS")
		)
		(fp_rect
			(start -0.508 0.9398)
			(end 0.508 -0.9398)
			(stroke
				(width 0)
				(type default)
			)
			(fill no)
			(layer "F.CrtYd")
		)
		(fp_rect
			(start -0.508 0.9398)
			(end 0.508 -0.9398)
			(stroke
				(width 0)
				(type default)
			)
			(fill no)
			(layer "F.Fab")
		)
		(pad "1" smd custom
			(at 0 -0.4445 270)
			(size 0.1397 0.1397)
			(layers "F.Cu" "F.Mask" "F.Paste")
			(net "SSD13_PWREN")
			(options
				(clearance outline)
				(anchor circle)
			)
			(primitives
				(gr_poly
					(pts
						(arc
							(start -0.1778 -0.2794)
							(mid -0.249642 -0.249642)
							(end -0.2794 -0.1778)
						)
						(arc
							(start -0.2794 0.1778)
							(mid -0.249642 0.249642)
							(end -0.1778 0.2794)
						)
						(arc
							(start 0.1778 0.2794)
							(mid 0.249642 0.249642)
							(end 0.2794 0.1778)
						)
						(arc
							(start 0.2794 -0.1778)
							(mid 0.249642 -0.249642)
							(end 0.1778 -0.2794)
						)
					)
					(width 0)
					(fill yes)
				)
			)
		)
		(pad "2" smd custom
			(at 0 0.4445 270)
			(size 0.1397 0.1397)
			(layers "F.Cu" "F.Mask" "F.Paste")
			(net "SSD13_PWREN_R")
			(options
				(clearance outline)
				(anchor circle)
			)
			(primitives
				(gr_poly
					(pts
						(arc
							(start -0.1778 -0.2794)
							(mid -0.249642 -0.249642)
							(end -0.2794 -0.1778)
						)
						(arc
							(start -0.2794 0.1778)
							(mid -0.249642 0.249642)
							(end -0.1778 0.2794)
						)
						(arc
							(start 0.1778 0.2794)
							(mid 0.249642 0.249642)
							(end 0.2794 0.1778)
						)
						(arc
							(start 0.2794 -0.1778)
							(mid 0.249642 -0.249642)
							(end 0.1778 -0.2794)
						)
					)
					(width 0)
					(fill yes)
				)
			)
		)
	)
	(footprint ""
		(layer "F.Cu")
		(at 46.823884 -447.929 90)
		(property "Reference" "Q53"
			(at 0 0 90)
			(layer "F.SilkS")
			(hide yes)
			(effects
				(font
					(size 1.27 1.27)
				)
			)
		)
		(property "Value" "2N7002A-7-GP"
			(at 0.127 -8.9662 90)
			(unlocked yes)
			(layer "F.Fab")
			(hide yes)
			(effects
				(font
					(size 1.016 1.016)
					(thickness 0.1524)
				)
			)
		)
		(property "Device Type" "SOT23DGS2D4H48"
			(at 0.127 -10.4902 90)
			(unlocked yes)
			(layer "F.Fab")
			(hide yes)
			(effects
				(font
					(size 1.016 1.016)
					(thickness 0.1524)
				)
			)
		)
		(duplicate_pad_numbers_are_jumpers no)
		(fp_line
			(start 1.651 -1.778)
			(end -1.651 -1.778)
			(stroke
				(width 0.1524)
				(type default)
			)
			(layer "F.SilkS")
		)
		(fp_line
			(start -1.651 -1.778)
			(end -1.651 1.778)
			(stroke
				(width 0.1524)
				(type default)
			)
			(layer "F.SilkS")
		)
		(fp_line
			(start 1.651 1.778)
			(end 1.651 -1.778)
			(stroke
				(width 0.1524)
				(type default)
			)
			(layer "F.SilkS")
		)
		(fp_line
			(start -1.651 1.778)
			(end 1.651 1.778)
			(stroke
				(width 0.1524)
				(type default)
			)
			(layer "F.SilkS")
		)
		(fp_poly
			(pts
				(xy -1.778 1.8796) (xy -1.778 -1.8796) (xy 1.778 -1.8796) (xy 1.778 1.8796)
			)
			(stroke
				(width 0)
				(type default)
			)
			(fill no)
			(layer "F.CrtYd")
		)
		(fp_poly
			(pts
				(xy -1.778 1.8796) (xy -1.778 -1.8796) (xy 1.778 -1.8796) (xy 1.778 1.8796)
			)
			(stroke
				(width 0)
				(type default)
			)
			(fill no)
			(layer "F.Fab")
		)
		(pad "D" smd custom
			(at 0 -0.9525 90)
			(size 0.1905 0.1905)
			(layers "F.Cu" "F.Mask" "F.Paste")
			(net "SSD_ACT_DR5_MOS_N")
			(options
				(clearance outline)
				(anchor circle)
			)
			(primitives
				(gr_poly
					(pts
						(arc
							(start -0.1778 0.5715)
							(mid -0.321484 0.511984)
							(end -0.381 0.3683)
						)
						(arc
							(start -0.381 -0.3683)
							(mid -0.321484 -0.511984)
							(end -0.1778 -0.5715)
						)
						(arc
							(start 0.1778 -0.5715)
							(mid 0.321484 -0.511984)
							(end 0.381 -0.3683)
						)
						(arc
							(start 0.381 0.3683)
							(mid 0.321484 0.511984)
							(end 0.1778 0.5715)
						)
					)
					(width 0)
					(fill yes)
				)
			)
		)
		(pad "G" smd custom
			(at -0.98425 0.9525 90)
			(size 0.1905 0.1905)
			(layers "F.Cu" "F.Mask" "F.Paste")
			(net "ATTN_LED_DR5_AND_R")
			(options
				(clearance outline)
				(anchor circle)
			)
			(primitives
				(gr_poly
					(pts
						(arc
							(start -0.1778 0.5715)
							(mid -0.321484 0.511984)
							(end -0.381 0.3683)
						)
						(arc
							(start -0.381 -0.3683)
							(mid -0.321484 -0.511984)
							(end -0.1778 -0.5715)
						)
						(arc
							(start 0.1778 -0.5715)
							(mid 0.321484 -0.511984)
							(end 0.381 -0.3683)
						)
						(arc
							(start 0.381 0.3683)
							(mid 0.321484 0.511984)
							(end 0.1778 0.5715)
						)
					)
					(width 0)
					(fill yes)
				)
			)
		)
		(pad "S" smd custom
			(at 0.98425 0.9525 90)
			(size 0.1905 0.1905)
			(layers "F.Cu" "F.Mask" "F.Paste")
			(net "SSD_ACT_DR5_R")
			(options
				(clearance outline)
				(anchor circle)
			)
			(primitives
				(gr_poly
					(pts
						(arc
							(start -0.1778 0.5715)
							(mid -0.321484 0.511984)
							(end -0.381 0.3683)
						)
						(arc
							(start -0.381 -0.3683)
							(mid -0.321484 -0.511984)
							(end -0.1778 -0.5715)
						)
						(arc
							(start 0.1778 -0.5715)
							(mid 0.321484 -0.511984)
							(end 0.381 -0.3683)
						)
						(arc
							(start 0.381 0.3683)
							(mid 0.321484 0.511984)
							(end 0.1778 0.5715)
						)
					)
					(width 0)
					(fill yes)
				)
			)
		)
	)
	(footprint ""
		(layer "F.Cu")
		(at 36.576 -371.094 180)
		(property "Reference" "PC1244"
			(at 0 0 180)
			(layer "F.SilkS")
			(hide yes)
			(effects
				(font
					(size 1.27 1.27)
				)
			)
		)
		(property "Value" "SCD1U25V3KX-GP"
			(at 0 -2.8194 180)
			(unlocked yes)
			(layer "F.Fab")
			(hide yes)
			(effects
				(font
					(size 1.016 1.016)
					(thickness 0.1524)
				)
			)
		)
		(property "Device Type" "C603H36"
			(at 0 -4.3434 180)
			(unlocked yes)
			(layer "F.Fab")
			(hide yes)
			(effects
				(font
					(size 1.016 1.016)
					(thickness 0.1524)
				)
			)
		)
		(duplicate_pad_numbers_are_jumpers no)
		(fp_line
			(start 0.508 0)
			(end -0.508 0)
			(stroke
				(width 0.2032)
				(type default)
			)
			(layer "F.SilkS")
		)
		(fp_rect
			(start -0.5842 1.3335)
			(end 0.5842 -1.3335)
			(stroke
				(width 0)
				(type default)
			)
			(fill no)
			(layer "F.CrtYd")
		)
		(fp_rect
			(start -0.5842 1.3335)
			(end 0.5842 -1.3335)
			(stroke
				(width 0)
				(type default)
			)
			(fill no)
			(layer "F.Fab")
		)
		(pad "1" smd custom
			(at 0 -0.762 180)
			(size 0.2159 0.2159)
			(layers "F.Cu" "F.Mask" "F.Paste")
			(net "P3V3")
			(options
				(clearance outline)
				(anchor circle)
			)
			(primitives
				(gr_poly
					(pts
						(arc
							(start -0.3302 -0.4318)
							(mid -0.402042 -0.402042)
							(end -0.4318 -0.3302)
						)
						(arc
							(start -0.4318 0.3302)
							(mid -0.402042 0.402042)
							(end -0.3302 0.4318)
						)
						(arc
							(start 0.3302 0.4318)
							(mid 0.402042 0.402042)
							(end 0.4318 0.3302)
						)
						(arc
							(start 0.4318 -0.3302)
							(mid 0.402042 -0.402042)
							(end 0.3302 -0.4318)
						)
					)
					(width 0)
					(fill yes)
				)
			)
		)
		(pad "2" smd custom
			(at 0 0.762 180)
			(size 0.2159 0.2159)
			(layers "F.Cu" "F.Mask" "F.Paste")
			(net "GND")
			(options
				(clearance outline)
				(anchor circle)
			)
			(primitives
				(gr_poly
					(pts
						(arc
							(start -0.3302 -0.4318)
							(mid -0.402042 -0.402042)
							(end -0.4318 -0.3302)
						)
						(arc
							(start -0.4318 0.3302)
							(mid -0.402042 0.402042)
							(end -0.3302 0.4318)
						)
						(arc
							(start 0.3302 0.4318)
							(mid 0.402042 0.402042)
							(end 0.4318 0.3302)
						)
						(arc
							(start 0.4318 -0.3302)
							(mid 0.402042 -0.402042)
							(end 0.3302 -0.4318)
						)
					)
					(width 0)
					(fill yes)
				)
			)
		)
	)
	(footprint ""
		(layer "F.Cu")
		(at 221.996 -91.44 180)
		(property "Reference" "PC1200"
			(at 0 0 180)
			(layer "F.SilkS")
			(hide yes)
			(effects
				(font
					(size 1.27 1.27)
				)
			)
		)
		(property "Value" "SC22U25V6KX-GP-U"
			(at -2.860802 -5.279644 180)
			(unlocked yes)
			(layer "F.Fab")
			(hide yes)
			(effects
				(font
					(size 1.016 1.016)
					(thickness 0.1524)
				)
			)
		)
		(property "Device Type" "C1206-TO0D3H75"
			(at -2.860802 -6.803644 180)
			(unlocked yes)
			(layer "F.Fab")
			(hide yes)
			(effects
				(font
					(size 1.016 1.016)
					(thickness 0.1524)
				)
			)
		)
		(duplicate_pad_numbers_are_jumpers no)
		(fp_line
			(start 1.3081 2.3749)
			(end -1.3081 2.3749)
			(stroke
				(width 0.1524)
				(type default)
			)
			(layer "F.SilkS")
		)
		(fp_line
			(start 1.3081 -2.3749)
			(end 1.3081 2.3749)
			(stroke
				(width 0.1524)
				(type default)
			)
			(layer "F.SilkS")
		)
		(fp_line
			(start -1.3081 2.3749)
			(end -1.3081 -2.3749)
			(stroke
				(width 0.1524)
				(type default)
			)
			(layer "F.SilkS")
		)
		(fp_line
			(start -1.3081 -2.3749)
			(end 1.3081 -2.3749)
			(stroke
				(width 0.1524)
				(type default)
			)
			(layer "F.SilkS")
		)
		(fp_rect
			(start -0.8001 1.6002)
			(end 0.8001 -1.6002)
			(stroke
				(width 0)
				(type default)
			)
			(fill no)
			(layer "F.CrtYd")
		)
		(fp_poly
			(pts
				(xy -1.5621 2.4511) (xy -1.5621 1.6002) (xy 0.8001 1.6002) (xy 0.8001 -1.6002) (xy -0.8001 -1.6002)
				(xy -0.8001 1.5875) (xy -1.5621 1.5875) (xy -1.5621 -2.4511) (xy 1.5621 -2.4511) (xy 1.5621 2.4511)
			)
			(stroke
				(width 0)
				(type default)
			)
			(fill no)
			(layer "F.CrtYd")
		)
		(fp_rect
			(start -1.5621 2.4511)
			(end 1.5621 -2.4511)
			(stroke
				(width 0)
				(type default)
			)
			(fill no)
			(layer "F.Fab")
		)
		(pad "1" smd rect
			(at 0 -1.392936 180)
			(size 2.1082 1.4478)
			(layers "F.Cu" "F.Mask" "F.Paste")
			(net "P12V_SSD4")
		)
		(pad "2" smd rect
			(at 0 1.392936 180)
			(size 2.1082 1.4478)
			(layers "F.Cu" "F.Mask" "F.Paste")
			(net "GND")
		)
	)
)
